(kicad_pcb
	(version 20260206)
	(generator "pcbnew")
	(generator_version "10.0")
	(general
		(thickness 1.6)
		(legacy_teardrops no)
	)
	(paper "A4")
	(title_block
		(title "03242023_DA0F0TMBIJ0_F0T_Motherboard_J_brd_V01_OCP.brd")
		(comment 1 "Grand Teton / footprints 1378-1383 of 6105")
	)
	(layers
		(0 "F.Cu" signal "TOP")
		(4 "In1.Cu" signal "GND")
		(6 "In2.Cu" signal "IN1")
		(8 "In3.Cu" signal "GND1")
		(10 "In4.Cu" signal "IN2")
		(12 "In5.Cu" signal "GND2")
		(14 "In6.Cu" signal "IN3")
		(16 "In7.Cu" signal "GND3")
		(18 "In8.Cu" signal "VCC")
		(20 "In9.Cu" signal "VCC1")
		(22 "In10.Cu" signal "GND4")
		(24 "In11.Cu" signal "IN4")
		(26 "In12.Cu" signal "GND5")
		(28 "In13.Cu" signal "IN5")
		(30 "In14.Cu" signal "GND6")
		(32 "In15.Cu" signal "IN6")
		(34 "In16.Cu" signal "GND7")
		(2 "B.Cu" signal "BOTTOM")
		(9 "F.Adhes" user "F.Adhesive")
		(11 "B.Adhes" user "B.Adhesive")
		(13 "F.Paste" user "Package Geometry/Pastemask Top")
		(15 "B.Paste" user "Package Geometry/Pastemask Bottom")
		(5 "F.SilkS" user "Ref Des/Silkscreen Top")
		(7 "B.SilkS" user "Ref Des/Silkscreen Bottom")
		(1 "F.Mask" user "Board Geometry/Soldermask Top")
		(3 "B.Mask" user "Board Geometry/Soldermask Bottom")
		(17 "Dwgs.User" user "User.Drawings")
		(19 "Cmts.User" user "User.Comments")
		(21 "Eco1.User" user "User.Eco1")
		(23 "Eco2.User" user "User.Eco2")
		(25 "Edge.Cuts" user "Board Geometry/Outline")
		(27 "Margin" user)
		(31 "F.CrtYd" user "Package Geometry/Place Bound Top")
		(29 "B.CrtYd" user "Package Geometry/Place Bound Bottom")
		(35 "F.Fab" user "Ref Des/Assembly Top")
		(33 "B.Fab" user "Ref Des/Assembly Bottom")
	)
	(footprint ""
		(layer "F.Cu")
		(at 216.1286 -120.142 180)
		(property "Reference" "C2369"
			(at 0 0 180)
			(layer "F.SilkS")
			(hide yes)
			(effects
				(font
					(size 1.27 1.27)
				)
			)
		)
		(property "Value" ""
			(at 0 0 180)
			(layer "F.Fab")
			(effects
				(font
					(size 1.27 1.27)
				)
			)
		)
		(duplicate_pad_numbers_are_jumpers no)
		(fp_line
			(start 0.7874 0.4064)
			(end -0.7874 0.4064)
			(stroke
				(width 0.1524)
				(type default)
			)
			(layer "F.SilkS")
		)
		(fp_line
			(start 0.7874 -0.4064)
			(end 0.7874 0.4064)
			(stroke
				(width 0.1524)
				(type default)
			)
			(layer "F.SilkS")
		)
		(fp_line
			(start -0.7874 0.4064)
			(end -0.7874 -0.4064)
			(stroke
				(width 0.1524)
				(type default)
			)
			(layer "F.SilkS")
		)
		(fp_line
			(start -0.7874 -0.4064)
			(end 0.7874 -0.4064)
			(stroke
				(width 0.1524)
				(type default)
			)
			(layer "F.SilkS")
		)
		(fp_line
			(start 0.67945 0.3048)
			(end 0.120396 0.3048)
			(stroke
				(width 0.1)
				(type default)
			)
			(layer "F.Fab")
		)
		(fp_line
			(start 0.67945 -0.3048)
			(end 0.67945 0.3048)
			(stroke
				(width 0.1)
				(type default)
			)
			(layer "F.Fab")
		)
		(fp_line
			(start 0.12065 -0.2794)
			(end 0.12065 -0.3048)
			(stroke
				(width 0.1)
				(type default)
			)
			(layer "F.Fab")
		)
		(fp_line
			(start 0.12065 -0.3048)
			(end 0.67945 -0.3048)
			(stroke
				(width 0.1)
				(type default)
			)
			(layer "F.Fab")
		)
		(fp_line
			(start 0.120396 0.3048)
			(end 0.120396 0.2794)
			(stroke
				(width 0.1)
				(type default)
			)
			(layer "F.Fab")
		)
		(fp_line
			(start 0.120396 0.2794)
			(end -0.12065 0.2794)
			(stroke
				(width 0.1)
				(type default)
			)
			(layer "F.Fab")
		)
		(fp_line
			(start -0.12065 0.3048)
			(end -0.67945 0.3048)
			(stroke
				(width 0.1)
				(type default)
			)
			(layer "F.Fab")
		)
		(fp_line
			(start -0.12065 0.2794)
			(end -0.12065 0.3048)
			(stroke
				(width 0.1)
				(type default)
			)
			(layer "F.Fab")
		)
		(fp_line
			(start -0.12065 -0.2794)
			(end 0.12065 -0.2794)
			(stroke
				(width 0.1)
				(type default)
			)
			(layer "F.Fab")
		)
		(fp_line
			(start -0.12065 -0.305054)
			(end -0.12065 -0.2794)
			(stroke
				(width 0.1)
				(type default)
			)
			(layer "F.Fab")
		)
		(fp_line
			(start -0.67945 0.3048)
			(end -0.67945 -0.305054)
			(stroke
				(width 0.1)
				(type default)
			)
			(layer "F.Fab")
		)
		(fp_line
			(start -0.67945 -0.305054)
			(end -0.12065 -0.305054)
			(stroke
				(width 0.1)
				(type default)
			)
			(layer "F.Fab")
		)
		(pad "1" smd circle
			(at -0.40005 0 180)
			(size 0 0)
			(layers "F.Cu" "F.Mask" "F.Paste")
			(net "FM_AC_PWR_BTN_R_N")
		)
		(pad "2" smd circle
			(at 0.40005 0 180)
			(size 0 0)
			(layers "F.Cu" "F.Mask" "F.Paste")
			(net "GND")
		)
	)
	(footprint ""
		(layer "F.Cu")
		(at 230.248206 -251.189236 180)
		(property "Reference" "R3336"
			(at 0 0 180)
			(layer "F.SilkS")
			(hide yes)
			(effects
				(font
					(size 1.27 1.27)
				)
			)
		)
		(property "Value" ""
			(at 0 0 180)
			(layer "F.Fab")
			(effects
				(font
					(size 1.27 1.27)
				)
			)
		)
		(duplicate_pad_numbers_are_jumpers no)
		(fp_line
			(start 0.7874 0.4064)
			(end -0.7874 0.4064)
			(stroke
				(width 0.1524)
				(type default)
			)
			(layer "F.SilkS")
		)
		(fp_line
			(start 0.7874 -0.4064)
			(end 0.7874 0.4064)
			(stroke
				(width 0.1524)
				(type default)
			)
			(layer "F.SilkS")
		)
		(fp_line
			(start -0.7874 0.4064)
			(end -0.7874 -0.4064)
			(stroke
				(width 0.1524)
				(type default)
			)
			(layer "F.SilkS")
		)
		(fp_line
			(start -0.7874 -0.4064)
			(end 0.7874 -0.4064)
			(stroke
				(width 0.1524)
				(type default)
			)
			(layer "F.SilkS")
		)
		(fp_line
			(start 0.67945 0.3048)
			(end 0.120396 0.3048)
			(stroke
				(width 0.1)
				(type default)
			)
			(layer "F.Fab")
		)
		(fp_line
			(start 0.67945 -0.3048)
			(end 0.67945 0.3048)
			(stroke
				(width 0.1)
				(type default)
			)
			(layer "F.Fab")
		)
		(fp_line
			(start 0.12065 -0.2794)
			(end 0.12065 -0.3048)
			(stroke
				(width 0.1)
				(type default)
			)
			(layer "F.Fab")
		)
		(fp_line
			(start 0.12065 -0.3048)
			(end 0.67945 -0.3048)
			(stroke
				(width 0.1)
				(type default)
			)
			(layer "F.Fab")
		)
		(fp_line
			(start 0.120396 0.3048)
			(end 0.120396 0.2794)
			(stroke
				(width 0.1)
				(type default)
			)
			(layer "F.Fab")
		)
		(fp_line
			(start 0.120396 0.2794)
			(end -0.12065 0.2794)
			(stroke
				(width 0.1)
				(type default)
			)
			(layer "F.Fab")
		)
		(fp_line
			(start -0.12065 0.3048)
			(end -0.67945 0.3048)
			(stroke
				(width 0.1)
				(type default)
			)
			(layer "F.Fab")
		)
		(fp_line
			(start -0.12065 0.2794)
			(end -0.12065 0.3048)
			(stroke
				(width 0.1)
				(type default)
			)
			(layer "F.Fab")
		)
		(fp_line
			(start -0.12065 -0.2794)
			(end 0.12065 -0.2794)
			(stroke
				(width 0.1)
				(type default)
			)
			(layer "F.Fab")
		)
		(fp_line
			(start -0.12065 -0.305054)
			(end -0.12065 -0.2794)
			(stroke
				(width 0.1)
				(type default)
			)
			(layer "F.Fab")
		)
		(fp_line
			(start -0.67945 0.3048)
			(end -0.67945 -0.305054)
			(stroke
				(width 0.1)
				(type default)
			)
			(layer "F.Fab")
		)
		(fp_line
			(start -0.67945 -0.305054)
			(end -0.12065 -0.305054)
			(stroke
				(width 0.1)
				(type default)
			)
			(layer "F.Fab")
		)
		(pad "1" smd circle
			(at -0.40005 0 180)
			(size 0 0)
			(layers "F.Cu" "F.Mask" "F.Paste")
			(net "CLK_100M_BMC_RC_DN_R")
		)
		(pad "2" smd circle
			(at 0.40005 0 180)
			(size 0 0)
			(layers "F.Cu" "F.Mask" "F.Paste")
			(net "CLK_100M_BMC_RC_DN")
		)
	)
	(footprint ""
		(layer "F.Cu")
		(at 365.46663 -249.320304 -90)
		(property "Reference" "C973"
			(at 0 0 270)
			(layer "F.SilkS")
			(hide yes)
			(effects
				(font
					(size 1.27 1.27)
				)
			)
		)
		(property "Value" ""
			(at 0 0 270)
			(layer "F.Fab")
			(effects
				(font
					(size 1.27 1.27)
				)
			)
		)
		(duplicate_pad_numbers_are_jumpers no)
		(fp_line
			(start -0.7874 0.4064)
			(end -0.7874 -0.4064)
			(stroke
				(width 0.1524)
				(type default)
			)
			(layer "F.SilkS")
		)
		(fp_line
			(start 0.7874 0.4064)
			(end -0.7874 0.4064)
			(stroke
				(width 0.1524)
				(type default)
			)
			(layer "F.SilkS")
		)
		(fp_line
			(start -0.7874 -0.4064)
			(end 0.7874 -0.4064)
			(stroke
				(width 0.1524)
				(type default)
			)
			(layer "F.SilkS")
		)
		(fp_line
			(start 0.7874 -0.4064)
			(end 0.7874 0.4064)
			(stroke
				(width 0.1524)
				(type default)
			)
			(layer "F.SilkS")
		)
		(fp_line
			(start -0.67945 0.3048)
			(end -0.67945 -0.305054)
			(stroke
				(width 0.1)
				(type default)
			)
			(layer "F.Fab")
		)
		(fp_line
			(start -0.12065 0.3048)
			(end -0.67945 0.3048)
			(stroke
				(width 0.1)
				(type default)
			)
			(layer "F.Fab")
		)
		(fp_line
			(start 0.120396 0.3048)
			(end 0.120396 0.2794)
			(stroke
				(width 0.1)
				(type default)
			)
			(layer "F.Fab")
		)
		(fp_line
			(start 0.67945 0.3048)
			(end 0.120396 0.3048)
			(stroke
				(width 0.1)
				(type default)
			)
			(layer "F.Fab")
		)
		(fp_line
			(start -0.12065 0.2794)
			(end -0.12065 0.3048)
			(stroke
				(width 0.1)
				(type default)
			)
			(layer "F.Fab")
		)
		(fp_line
			(start 0.120396 0.2794)
			(end -0.12065 0.2794)
			(stroke
				(width 0.1)
				(type default)
			)
			(layer "F.Fab")
		)
		(fp_line
			(start -0.12065 -0.2794)
			(end 0.12065 -0.2794)
			(stroke
				(width 0.1)
				(type default)
			)
			(layer "F.Fab")
		)
		(fp_line
			(start 0.12065 -0.2794)
			(end 0.12065 -0.3048)
			(stroke
				(width 0.1)
				(type default)
			)
			(layer "F.Fab")
		)
		(fp_line
			(start 0.12065 -0.3048)
			(end 0.67945 -0.3048)
			(stroke
				(width 0.1)
				(type default)
			)
			(layer "F.Fab")
		)
		(fp_line
			(start 0.67945 -0.3048)
			(end 0.67945 0.3048)
			(stroke
				(width 0.1)
				(type default)
			)
			(layer "F.Fab")
		)
		(fp_line
			(start -0.67945 -0.305054)
			(end -0.12065 -0.305054)
			(stroke
				(width 0.1)
				(type default)
			)
			(layer "F.Fab")
		)
		(fp_line
			(start -0.12065 -0.305054)
			(end -0.12065 -0.2794)
			(stroke
				(width 0.1)
				(type default)
			)
			(layer "F.Fab")
		)
		(pad "1" smd circle
			(at -0.40005 0 270)
			(size 0 0)
			(layers "F.Cu" "F.Mask" "F.Paste")
			(net "PVCCIN_CPU0")
		)
		(pad "2" smd circle
			(at 0.40005 0 270)
			(size 0 0)
			(layers "F.Cu" "F.Mask" "F.Paste")
			(net "GND")
		)
	)
	(footprint ""
		(layer "F.Cu")
		(at 396.822168 -165.363906 180)
		(property "Reference" "PR4237"
			(at 0 0 180)
			(layer "F.SilkS")
			(hide yes)
			(effects
				(font
					(size 1.27 1.27)
				)
			)
		)
		(property "Value" ""
			(at 0 0 180)
			(layer "F.Fab")
			(effects
				(font
					(size 1.27 1.27)
				)
			)
		)
		(duplicate_pad_numbers_are_jumpers no)
		(fp_line
			(start 0.7874 0.4064)
			(end -0.7874 0.4064)
			(stroke
				(width 0.1524)
				(type default)
			)
			(layer "F.SilkS")
		)
		(fp_line
			(start 0.7874 -0.4064)
			(end 0.7874 0.4064)
			(stroke
				(width 0.1524)
				(type default)
			)
			(layer "F.SilkS")
		)
		(fp_line
			(start -0.7874 0.4064)
			(end -0.7874 -0.4064)
			(stroke
				(width 0.1524)
				(type default)
			)
			(layer "F.SilkS")
		)
		(fp_line
			(start -0.7874 -0.4064)
			(end 0.7874 -0.4064)
			(stroke
				(width 0.1524)
				(type default)
			)
			(layer "F.SilkS")
		)
		(fp_line
			(start 0.67945 0.3048)
			(end 0.120396 0.3048)
			(stroke
				(width 0.1)
				(type default)
			)
			(layer "F.Fab")
		)
		(fp_line
			(start 0.67945 -0.3048)
			(end 0.67945 0.3048)
			(stroke
				(width 0.1)
				(type default)
			)
			(layer "F.Fab")
		)
		(fp_line
			(start 0.12065 -0.2794)
			(end 0.12065 -0.3048)
			(stroke
				(width 0.1)
				(type default)
			)
			(layer "F.Fab")
		)
		(fp_line
			(start 0.12065 -0.3048)
			(end 0.67945 -0.3048)
			(stroke
				(width 0.1)
				(type default)
			)
			(layer "F.Fab")
		)
		(fp_line
			(start 0.120396 0.3048)
			(end 0.120396 0.2794)
			(stroke
				(width 0.1)
				(type default)
			)
			(layer "F.Fab")
		)
		(fp_line
			(start 0.120396 0.2794)
			(end -0.12065 0.2794)
			(stroke
				(width 0.1)
				(type default)
			)
			(layer "F.Fab")
		)
		(fp_line
			(start -0.12065 0.3048)
			(end -0.67945 0.3048)
			(stroke
				(width 0.1)
				(type default)
			)
			(layer "F.Fab")
		)
		(fp_line
			(start -0.12065 0.2794)
			(end -0.12065 0.3048)
			(stroke
				(width 0.1)
				(type default)
			)
			(layer "F.Fab")
		)
		(fp_line
			(start -0.12065 -0.2794)
			(end 0.12065 -0.2794)
			(stroke
				(width 0.1)
				(type default)
			)
			(layer "F.Fab")
		)
		(fp_line
			(start -0.12065 -0.305054)
			(end -0.12065 -0.2794)
			(stroke
				(width 0.1)
				(type default)
			)
			(layer "F.Fab")
		)
		(fp_line
			(start -0.67945 0.3048)
			(end -0.67945 -0.305054)
			(stroke
				(width 0.1)
				(type default)
			)
			(layer "F.Fab")
		)
		(fp_line
			(start -0.67945 -0.305054)
			(end -0.12065 -0.305054)
			(stroke
				(width 0.1)
				(type default)
			)
			(layer "F.Fab")
		)
		(pad "1" smd circle
			(at -0.40005 0 180)
			(size 0 0)
			(layers "F.Cu" "F.Mask" "F.Paste")
			(net "PVCCD_HV_CPU0")
		)
		(pad "2" smd circle
			(at 0.40005 0 180)
			(size 0 0)
			(layers "F.Cu" "F.Mask" "F.Paste")
			(net "GND")
		)
	)
	(footprint ""
		(layer "F.Cu")
		(at 354.264214 -251.375418 90)
		(property "Reference" "C1022"
			(at 0 0 90)
			(layer "F.SilkS")
			(hide yes)
			(effects
				(font
					(size 1.27 1.27)
				)
			)
		)
		(property "Value" ""
			(at 0 0 90)
			(layer "F.Fab")
			(effects
				(font
					(size 1.27 1.27)
				)
			)
		)
		(duplicate_pad_numbers_are_jumpers no)
		(fp_line
			(start 0.7874 -0.4064)
			(end 0.7874 0.4064)
			(stroke
				(width 0.1524)
				(type default)
			)
			(layer "F.SilkS")
		)
		(fp_line
			(start -0.7874 -0.4064)
			(end 0.7874 -0.4064)
			(stroke
				(width 0.1524)
				(type default)
			)
			(layer "F.SilkS")
		)
		(fp_line
			(start 0.7874 0.4064)
			(end -0.7874 0.4064)
			(stroke
				(width 0.1524)
				(type default)
			)
			(layer "F.SilkS")
		)
		(fp_line
			(start -0.7874 0.4064)
			(end -0.7874 -0.4064)
			(stroke
				(width 0.1524)
				(type default)
			)
			(layer "F.SilkS")
		)
		(fp_line
			(start -0.12065 -0.305054)
			(end -0.12065 -0.2794)
			(stroke
				(width 0.1)
				(type default)
			)
			(layer "F.Fab")
		)
		(fp_line
			(start -0.67945 -0.305054)
			(end -0.12065 -0.305054)
			(stroke
				(width 0.1)
				(type default)
			)
			(layer "F.Fab")
		)
		(fp_line
			(start 0.67945 -0.3048)
			(end 0.67945 0.3048)
			(stroke
				(width 0.1)
				(type default)
			)
			(layer "F.Fab")
		)
		(fp_line
			(start 0.12065 -0.3048)
			(end 0.67945 -0.3048)
			(stroke
				(width 0.1)
				(type default)
			)
			(layer "F.Fab")
		)
		(fp_line
			(start 0.12065 -0.2794)
			(end 0.12065 -0.3048)
			(stroke
				(width 0.1)
				(type default)
			)
			(layer "F.Fab")
		)
		(fp_line
			(start -0.12065 -0.2794)
			(end 0.12065 -0.2794)
			(stroke
				(width 0.1)
				(type default)
			)
			(layer "F.Fab")
		)
		(fp_line
			(start 0.120396 0.2794)
			(end -0.12065 0.2794)
			(stroke
				(width 0.1)
				(type default)
			)
			(layer "F.Fab")
		)
		(fp_line
			(start -0.12065 0.2794)
			(end -0.12065 0.3048)
			(stroke
				(width 0.1)
				(type default)
			)
			(layer "F.Fab")
		)
		(fp_line
			(start 0.67945 0.3048)
			(end 0.120396 0.3048)
			(stroke
				(width 0.1)
				(type default)
			)
			(layer "F.Fab")
		)
		(fp_line
			(start 0.120396 0.3048)
			(end 0.120396 0.2794)
			(stroke
				(width 0.1)
				(type default)
			)
			(layer "F.Fab")
		)
		(fp_line
			(start -0.12065 0.3048)
			(end -0.67945 0.3048)
			(stroke
				(width 0.1)
				(type default)
			)
			(layer "F.Fab")
		)
		(fp_line
			(start -0.67945 0.3048)
			(end -0.67945 -0.305054)
			(stroke
				(width 0.1)
				(type default)
			)
			(layer "F.Fab")
		)
		(pad "1" smd circle
			(at -0.40005 0 90)
			(size 0 0)
			(layers "F.Cu" "F.Mask" "F.Paste")
			(net "PVCCIN_CPU0")
		)
		(pad "2" smd circle
			(at 0.40005 0 90)
			(size 0 0)
			(layers "F.Cu" "F.Mask" "F.Paste")
			(net "GND")
		)
	)
	(footprint ""
		(layer "F.Cu")
		(at 131.78155 -42.784522 180)
		(property "Reference" "R491"
			(at 0 0 180)
			(layer "F.SilkS")
			(hide yes)
			(effects
				(font
					(size 1.27 1.27)
				)
			)
		)
		(property "Value" ""
			(at 0 0 180)
			(layer "F.Fab")
			(effects
				(font
					(size 1.27 1.27)
				)
			)
		)
		(duplicate_pad_numbers_are_jumpers no)
		(fp_line
			(start 0.7874 0.4064)
			(end -0.7874 0.4064)
			(stroke
				(width 0.1524)
				(type default)
			)
			(layer "F.SilkS")
		)
		(fp_line
			(start 0.7874 -0.4064)
			(end 0.7874 0.4064)
			(stroke
				(width 0.1524)
				(type default)
			)
			(layer "F.SilkS")
		)
		(fp_line
			(start -0.7874 0.4064)
			(end -0.7874 -0.4064)
			(stroke
				(width 0.1524)
				(type default)
			)
			(layer "F.SilkS")
		)
		(fp_line
			(start -0.7874 -0.4064)
			(end 0.7874 -0.4064)
			(stroke
				(width 0.1524)
				(type default)
			)
			(layer "F.SilkS")
		)
		(fp_line
			(start 0.67945 0.3048)
			(end 0.120396 0.3048)
			(stroke
				(width 0.1)
				(type default)
			)
			(layer "F.Fab")
		)
		(fp_line
			(start 0.67945 -0.3048)
			(end 0.67945 0.3048)
			(stroke
				(width 0.1)
				(type default)
			)
			(layer "F.Fab")
		)
		(fp_line
			(start 0.12065 -0.2794)
			(end 0.12065 -0.3048)
			(stroke
				(width 0.1)
				(type default)
			)
			(layer "F.Fab")
		)
		(fp_line
			(start 0.12065 -0.3048)
			(end 0.67945 -0.3048)
			(stroke
				(width 0.1)
				(type default)
			)
			(layer "F.Fab")
		)
		(fp_line
			(start 0.120396 0.3048)
			(end 0.120396 0.2794)
			(stroke
				(width 0.1)
				(type default)
			)
			(layer "F.Fab")
		)
		(fp_line
			(start 0.120396 0.2794)
			(end -0.12065 0.2794)
			(stroke
				(width 0.1)
				(type default)
			)
			(layer "F.Fab")
		)
		(fp_line
			(start -0.12065 0.3048)
			(end -0.67945 0.3048)
			(stroke
				(width 0.1)
				(type default)
			)
			(layer "F.Fab")
		)
		(fp_line
			(start -0.12065 0.2794)
			(end -0.12065 0.3048)
			(stroke
				(width 0.1)
				(type default)
			)
			(layer "F.Fab")
		)
		(fp_line
			(start -0.12065 -0.2794)
			(end 0.12065 -0.2794)
			(stroke
				(width 0.1)
				(type default)
			)
			(layer "F.Fab")
		)
		(fp_line
			(start -0.12065 -0.305054)
			(end -0.12065 -0.2794)
			(stroke
				(width 0.1)
				(type default)
			)
			(layer "F.Fab")
		)
		(fp_line
			(start -0.67945 0.3048)
			(end -0.67945 -0.305054)
			(stroke
				(width 0.1)
				(type default)
			)
			(layer "F.Fab")
		)
		(fp_line
			(start -0.67945 -0.305054)
			(end -0.12065 -0.305054)
			(stroke
				(width 0.1)
				(type default)
			)
			(layer "F.Fab")
		)
		(pad "1" smd circle
			(at -0.40005 0 180)
			(size 0 0)
			(layers "F.Cu" "F.Mask" "F.Paste")
			(net "M2_SSD0_CLKREQ_EN_N")
		)
		(pad "2" smd circle
			(at 0.40005 0 180)
			(size 0 0)
			(layers "F.Cu" "F.Mask" "F.Paste")
			(net "GND")
		)
	)
)
